# S9S_MB_2U (Grand Teton) — schematic netlist excerpt (pin names and nets, part order shuffled) for the footprints in the layout excerpt that follows; sources: Cadence DE-HDL packaged netlist, KiCad conversion of 03242023_DA0F0TMBIJ0_F0T_Motherboard_J_brd_V01_OCP.brd

C719  Q_CAP_DIFFBUS  DIFF BUS_0.22UF 6.3V 20% X6S  pkg C0201  page 176 : \1\ = P5E_CPU1_PE0_TX_C_DP<11> ; \2\ = P5E_CPU1_PE0_TX_DP<11>
PC337  Q_CAP  1UF 16V 10% X6S  pkg C0402  page 266 : A = PVCCIN_CPU0_VCC ; B = GND
C1323  Q_CAP  0.1UF 25V 10% X7R  pkg 0402  page 194 : A = P1V8_PCH_AUX ; B = GND

(kicad_pcb
	(version 20260206)
	(generator "pcbnew")
	(generator_version "10.0")
	(general
		(thickness 1.6)
		(legacy_teardrops no)
	)
	(paper "A4")
	(title_block
		(title "03242023_DA0F0TMBIJ0_F0T_Motherboard_J_brd_V01_OCP.brd")
		(comment 1 "Grand Teton / footprints 1342-1344 of 6105")
	)
	(layers
		(0 "F.Cu" signal "TOP")
		(4 "In1.Cu" signal "GND")
		(6 "In2.Cu" signal "IN1")
		(8 "In3.Cu" signal "GND1")
		(10 "In4.Cu" signal "IN2")
		(12 "In5.Cu" signal "GND2")
		(14 "In6.Cu" signal "IN3")
		(16 "In7.Cu" signal "GND3")
		(18 "In8.Cu" signal "VCC")
		(20 "In9.Cu" signal "VCC1")
		(22 "In10.Cu" signal "GND4")
		(24 "In11.Cu" signal "IN4")
		(26 "In12.Cu" signal "GND5")
		(28 "In13.Cu" signal "IN5")
		(30 "In14.Cu" signal "GND6")
		(32 "In15.Cu" signal "IN6")
		(34 "In16.Cu" signal "GND7")
		(2 "B.Cu" signal "BOTTOM")
		(9 "F.Adhes" user "F.Adhesive")
		(11 "B.Adhes" user "B.Adhesive")
		(13 "F.Paste" user "Package Geometry/Pastemask Top")
		(15 "B.Paste" user "Package Geometry/Pastemask Bottom")
		(5 "F.SilkS" user "Ref Des/Silkscreen Top")
		(7 "B.SilkS" user "Ref Des/Silkscreen Bottom")
		(1 "F.Mask" user "Board Geometry/Soldermask Top")
		(3 "B.Mask" user "Board Geometry/Soldermask Bottom")
		(17 "Dwgs.User" user "User.Drawings")
		(19 "Cmts.User" user "User.Comments")
		(21 "Eco1.User" user "User.Eco1")
		(23 "Eco2.User" user "User.Eco2")
		(25 "Edge.Cuts" user "Board Geometry/Outline")
		(27 "Margin" user)
		(31 "F.CrtYd" user "Package Geometry/Place Bound Top")
		(29 "B.CrtYd" user "Package Geometry/Place Bound Bottom")
		(35 "F.Fab" user "Ref Des/Assembly Top")
		(33 "B.Fab" user "Ref Des/Assembly Bottom")
	)
	(footprint ""
		(layer "F.Cu")
		(at 148.13788 -58.638948 180)
		(property "Reference" "C1323"
			(at 0 0 180)
			(layer "F.SilkS")
			(hide yes)
			(effects
				(font
					(size 1.27 1.27)
				)
			)
		)
		(property "Value" ""
			(at 0 0 180)
			(layer "F.Fab")
			(effects
				(font
					(size 1.27 1.27)
				)
			)
		)
		(duplicate_pad_numbers_are_jumpers no)
		(fp_line
			(start 0.7874 0.4064)
			(end -0.7874 0.4064)
			(stroke
				(width 0.1524)
				(type default)
			)
			(layer "F.SilkS")
		)
		(fp_line
			(start 0.7874 -0.4064)
			(end 0.7874 0.4064)
			(stroke
				(width 0.1524)
				(type default)
			)
			(layer "F.SilkS")
		)
		(fp_line
			(start -0.7874 0.4064)
			(end -0.7874 -0.4064)
			(stroke
				(width 0.1524)
				(type default)
			)
			(layer "F.SilkS")
		)
		(fp_line
			(start -0.7874 -0.4064)
			(end 0.7874 -0.4064)
			(stroke
				(width 0.1524)
				(type default)
			)
			(layer "F.SilkS")
		)
		(fp_line
			(start 0.67945 0.3048)
			(end 0.120396 0.3048)
			(stroke
				(width 0.1)
				(type default)
			)
			(layer "F.Fab")
		)
		(fp_line
			(start 0.67945 -0.3048)
			(end 0.67945 0.3048)
			(stroke
				(width 0.1)
				(type default)
			)
			(layer "F.Fab")
		)
		(fp_line
			(start 0.12065 -0.2794)
			(end 0.12065 -0.3048)
			(stroke
				(width 0.1)
				(type default)
			)
			(layer "F.Fab")
		)
		(fp_line
			(start 0.12065 -0.3048)
			(end 0.67945 -0.3048)
			(stroke
				(width 0.1)
				(type default)
			)
			(layer "F.Fab")
		)
		(fp_line
			(start 0.120396 0.3048)
			(end 0.120396 0.2794)
			(stroke
				(width 0.1)
				(type default)
			)
			(layer "F.Fab")
		)
		(fp_line
			(start 0.120396 0.2794)
			(end -0.12065 0.2794)
			(stroke
				(width 0.1)
				(type default)
			)
			(layer "F.Fab")
		)
		(fp_line
			(start -0.12065 0.3048)
			(end -0.67945 0.3048)
			(stroke
				(width 0.1)
				(type default)
			)
			(layer "F.Fab")
		)
		(fp_line
			(start -0.12065 0.2794)
			(end -0.12065 0.3048)
			(stroke
				(width 0.1)
				(type default)
			)
			(layer "F.Fab")
		)
		(fp_line
			(start -0.12065 -0.2794)
			(end 0.12065 -0.2794)
			(stroke
				(width 0.1)
				(type default)
			)
			(layer "F.Fab")
		)
		(fp_line
			(start -0.12065 -0.305054)
			(end -0.12065 -0.2794)
			(stroke
				(width 0.1)
				(type default)
			)
			(layer "F.Fab")
		)
		(fp_line
			(start -0.67945 0.3048)
			(end -0.67945 -0.305054)
			(stroke
				(width 0.1)
				(type default)
			)
			(layer "F.Fab")
		)
		(fp_line
			(start -0.67945 -0.305054)
			(end -0.12065 -0.305054)
			(stroke
				(width 0.1)
				(type default)
			)
			(layer "F.Fab")
		)
		(pad "1" smd circle
			(at -0.40005 0 180)
			(size 0 0)
			(layers "F.Cu" "F.Mask" "F.Paste")
			(net "P1V8_PCH_AUX")
		)
		(pad "2" smd circle
			(at 0.40005 0 180)
			(size 0 0)
			(layers "F.Cu" "F.Mask" "F.Paste")
			(net "GND")
		)
	)
	(footprint ""
		(layer "F.Cu")
		(at 362.646468 -361.72775)
		(property "Reference" "PC337"
			(at 0 0 0)
			(layer "F.SilkS")
			(hide yes)
			(effects
				(font
					(size 1.27 1.27)
				)
			)
		)
		(property "Value" ""
			(at 0 0 0)
			(layer "F.Fab")
			(effects
				(font
					(size 1.27 1.27)
				)
			)
		)
		(duplicate_pad_numbers_are_jumpers no)
		(fp_line
			(start -0.7874 -0.4064)
			(end 0.7874 -0.4064)
			(stroke
				(width 0.1524)
				(type default)
			)
			(layer "F.SilkS")
		)
		(fp_line
			(start -0.7874 0.4064)
			(end -0.7874 -0.4064)
			(stroke
				(width 0.1524)
				(type default)
			)
			(layer "F.SilkS")
		)
		(fp_line
			(start 0.7874 -0.4064)
			(end 0.7874 0.4064)
			(stroke
				(width 0.1524)
				(type default)
			)
			(layer "F.SilkS")
		)
		(fp_line
			(start 0.7874 0.4064)
			(end -0.7874 0.4064)
			(stroke
				(width 0.1524)
				(type default)
			)
			(layer "F.SilkS")
		)
		(fp_line
			(start -0.67945 -0.305054)
			(end -0.12065 -0.305054)
			(stroke
				(width 0.1)
				(type default)
			)
			(layer "F.Fab")
		)
		(fp_line
			(start -0.67945 0.3048)
			(end -0.67945 -0.305054)
			(stroke
				(width 0.1)
				(type default)
			)
			(layer "F.Fab")
		)
		(fp_line
			(start -0.12065 -0.305054)
			(end -0.12065 -0.2794)
			(stroke
				(width 0.1)
				(type default)
			)
			(layer "F.Fab")
		)
		(fp_line
			(start -0.12065 -0.2794)
			(end 0.12065 -0.2794)
			(stroke
				(width 0.1)
				(type default)
			)
			(layer "F.Fab")
		)
		(fp_line
			(start -0.12065 0.2794)
			(end -0.12065 0.3048)
			(stroke
				(width 0.1)
				(type default)
			)
			(layer "F.Fab")
		)
		(fp_line
			(start -0.12065 0.3048)
			(end -0.67945 0.3048)
			(stroke
				(width 0.1)
				(type default)
			)
			(layer "F.Fab")
		)
		(fp_line
			(start 0.120396 0.2794)
			(end -0.12065 0.2794)
			(stroke
				(width 0.1)
				(type default)
			)
			(layer "F.Fab")
		)
		(fp_line
			(start 0.120396 0.3048)
			(end 0.120396 0.2794)
			(stroke
				(width 0.1)
				(type default)
			)
			(layer "F.Fab")
		)
		(fp_line
			(start 0.12065 -0.3048)
			(end 0.67945 -0.3048)
			(stroke
				(width 0.1)
				(type default)
			)
			(layer "F.Fab")
		)
		(fp_line
			(start 0.12065 -0.2794)
			(end 0.12065 -0.3048)
			(stroke
				(width 0.1)
				(type default)
			)
			(layer "F.Fab")
		)
		(fp_line
			(start 0.67945 -0.3048)
			(end 0.67945 0.3048)
			(stroke
				(width 0.1)
				(type default)
			)
			(layer "F.Fab")
		)
		(fp_line
			(start 0.67945 0.3048)
			(end 0.120396 0.3048)
			(stroke
				(width 0.1)
				(type default)
			)
			(layer "F.Fab")
		)
		(pad "1" smd circle
			(at -0.40005 0)
			(size 0 0)
			(layers "F.Cu" "F.Mask" "F.Paste")
			(net "PVCCIN_CPU0_VCC")
		)
		(pad "2" smd circle
			(at 0.40005 0)
			(size 0 0)
			(layers "F.Cu" "F.Mask" "F.Paste")
			(net "GND")
		)
	)
	(footprint ""
		(layer "F.Cu")
		(at 61.121798 -402.371052 -90)
		(property "Reference" "C719"
			(at 0 0 270)
			(layer "F.SilkS")
			(hide yes)
			(effects
				(font
					(size 1.27 1.27)
				)
			)
		)
		(property "Value" ""
			(at 0 0 270)
			(layer "F.Fab")
			(effects
				(font
					(size 1.27 1.27)
				)
			)
		)
		(duplicate_pad_numbers_are_jumpers no)
		(fp_line
			(start -0.299974 0.150114)
			(end -0.299974 -0.150114)
			(stroke
				(width 0.1)
				(type default)
			)
			(layer "F.Fab")
		)
		(fp_line
			(start 0.299974 0.150114)
			(end -0.299974 0.150114)
			(stroke
				(width 0.1)
				(type default)
			)
			(layer "F.Fab")
		)
		(fp_line
			(start -0.299974 -0.150114)
			(end 0.299974 -0.150114)
			(stroke
				(width 0.1)
				(type default)
			)
			(layer "F.Fab")
		)
		(fp_line
			(start 0.299974 -0.150114)
			(end 0.299974 0.150114)
			(stroke
				(width 0.1)
				(type default)
			)
			(layer "F.Fab")
		)
		(pad "1" smd rect
			(at -0.2667 0 270)
			(size 0.3048 0.381)
			(layers "F.Cu" "F.Mask" "F.Paste")
			(net "P5E_CPU1_PE0_TX_C_DP<11>")
		)
		(pad "2" smd rect
			(at 0.2667 0 270)
			(size 0.3048 0.381)
			(layers "F.Cu" "F.Mask" "F.Paste")
			(net "P5E_CPU1_PE0_TX_DP<11>")
		)
	)
)
